#ISCELL
  mstr_misc dns *
  *
#ISCELL
  mstr_misc prelim *
  *
#ISCELL
  mstr_symbols cad_note *
  *
#ISCELL
  mstr_symbols intel_corp_bpage *
  *
#ISCELL
  mstr_symbols gnd *
  page221_i1
#ISCELL
  mstr_symbols gnd *
  page221_i10
#CELL
  mstr_discrete cap *
  page221_i11
#ISCELL
  mstr_symbols gnd *
  page221_i12
#CELL
  mstr_discrete cap *
  page221_i13
#CELL
  mstr_discrete res *
  page221_i14
#CELL
  mstr_vreg mic5166 *
  page221_i15
#ISCELL
  mstr_symbols gnd *
  page221_i16
#ISCELL
  mstr_symbols gnd *
  page221_i17
#CELL
  mstr_discrete cap *
  page221_i18
#CELL
  mstr_discrete cap *
  page221_i19
#CELL
  mstr_discrete cap *
  page221_i2
#ISCELL
  mstr_symbols gnd *
  page221_i20
#ISCELL
  mstr_symbols gnd *
  page221_i21
#CELL
  mstr_discrete cap *
  page221_i22
#ISCELL
  mstr_symbols gnd *
  page221_i23
#CELL
  mstr_discrete cap *
  page221_i24
#CELL
  mstr_discrete res *
  page221_i25
#ISCELL
  mstr_symbols p3v3 *
  page221_i26
#ISCELL
  mstr_symbols pvtt_abc *
  page221_i28
#ISCELL
  mstr_standard offpage *
  page221_i3
#CELL
  mstr_discrete cap *
  page221_i30
#ISCELL
  mstr_symbols gnd *
  page221_i32
#CELL
  mstr_discrete res *
  page221_i33
#ISCELL
  mstr_symbols pvtt_abc *
  page221_i34
#ISCELL
  mstr_standard offpage *
  page221_i35
#ISCELL
  mstr_symbols gnd *
  page221_i36
#CELL
  mstr_discrete res *
  page221_i4
#CELL
  dev_discrete cap_a *
  page221_i40
#CELL
  mstr_discrete cap *
  page221_i44
#CELL
  mstr_discrete cap *
  page221_i45
#CELL
  mstr_discrete cap *
  page221_i46
#CELL
  mstr_discrete res *
  page221_i5
#CELL
  mstr_discrete res *
  page221_i6
#ISCELL
  mstr_symbols p3v3 *
  page221_i7
#ISCELL
  mstr_symbols pvddq_abc *
  page221_i8
#CELL
  mstr_misc shunt *
  page221_i9
